(kicad_pcb
	(version 20260206)
	(generator "pcbnew")
	(generator_version "10.0")
	(general
		(thickness 1.6)
		(legacy_teardrops no)
	)
	(paper "A4")
	(title_block
		(title "01162023_DA0F0TEBIF0_F0T_Expander_BD_F_brd_V02_OCP.brd")
		(comment 1 "Grand Teton / footprints 8204-8211 of 9728")
	)
	(layers
		(0 "F.Cu" signal "TOP")
		(4 "In1.Cu" signal "GND")
		(6 "In2.Cu" signal "VCC")
		(8 "In3.Cu" signal "VCC1")
		(10 "In4.Cu" signal "GND1")
		(12 "In5.Cu" signal "IN1")
		(14 "In6.Cu" signal "GND2")
		(16 "In7.Cu" signal "IN2")
		(18 "In8.Cu" signal "GND3")
		(20 "In9.Cu" signal "IN3")
		(22 "In10.Cu" signal "GND4")
		(24 "In11.Cu" signal "IN4")
		(26 "In12.Cu" signal "GND5")
		(28 "In13.Cu" signal "IN5")
		(30 "In14.Cu" signal "GND6")
		(32 "In15.Cu" signal "IN6")
		(34 "In16.Cu" signal "GND7")
		(2 "B.Cu" signal "BOTTOM")
		(9 "F.Adhes" user "F.Adhesive")
		(11 "B.Adhes" user "B.Adhesive")
		(13 "F.Paste" user "Package Geometry/Pastemask Top")
		(15 "B.Paste" user "Package Geometry/Pastemask Bottom")
		(5 "F.SilkS" user "Ref Des/Silkscreen Top")
		(7 "B.SilkS" user "Ref Des/Silkscreen Bottom")
		(1 "F.Mask" user "Board Geometry/Soldermask Top")
		(3 "B.Mask" user "Board Geometry/Soldermask Bottom")
		(17 "Dwgs.User" user "User.Drawings")
		(19 "Cmts.User" user "User.Comments")
		(21 "Eco1.User" user "User.Eco1")
		(23 "Eco2.User" user "User.Eco2")
		(25 "Edge.Cuts" user "Board Geometry/Outline")
		(27 "Margin" user)
		(31 "F.CrtYd" user "Package Geometry/Place Bound Top")
		(29 "B.CrtYd" user "Package Geometry/Place Bound Bottom")
		(35 "F.Fab" user "Ref Des/Assembly Top")
		(33 "B.Fab" user "Ref Des/Assembly Bottom")
	)
	(footprint ""
		(layer "B.Cu")
		(at 4.581398 -384.554476 -90)
		(property "Reference" "C4461"
			(at 0 0 90)
			(layer "B.SilkS")
			(hide yes)
			(effects
				(font
					(size 1.27 1.27)
				)
				(justify mirror)
			)
		)
		(property "Value" ""
			(at 0 0 90)
			(layer "B.Fab")
			(effects
				(font
					(size 1.27 1.27)
				)
				(justify mirror)
			)
		)
		(duplicate_pad_numbers_are_jumpers no)
		(fp_line
			(start -0.7874 0.4064)
			(end 0.7874 0.4064)
			(stroke
				(width 0.1524)
				(type default)
			)
			(layer "B.SilkS")
		)
		(fp_line
			(start 0.7874 0.4064)
			(end 0.7874 -0.4064)
			(stroke
				(width 0.1524)
				(type default)
			)
			(layer "B.SilkS")
		)
		(fp_line
			(start -0.7874 -0.4064)
			(end -0.7874 0.4064)
			(stroke
				(width 0.1524)
				(type default)
			)
			(layer "B.SilkS")
		)
		(fp_line
			(start 0.7874 -0.4064)
			(end -0.7874 -0.4064)
			(stroke
				(width 0.1524)
				(type default)
			)
			(layer "B.SilkS")
		)
		(fp_line
			(start -0.67945 0.3048)
			(end -0.120396 0.3048)
			(stroke
				(width 0.1)
				(type default)
			)
			(layer "B.Fab")
		)
		(fp_line
			(start -0.120396 0.3048)
			(end -0.120396 0.2794)
			(stroke
				(width 0.1)
				(type default)
			)
			(layer "B.Fab")
		)
		(fp_line
			(start 0.12065 0.3048)
			(end 0.67945 0.3048)
			(stroke
				(width 0.1)
				(type default)
			)
			(layer "B.Fab")
		)
		(fp_line
			(start 0.67945 0.3048)
			(end 0.67945 -0.305054)
			(stroke
				(width 0.1)
				(type default)
			)
			(layer "B.Fab")
		)
		(fp_line
			(start -0.120396 0.2794)
			(end 0.12065 0.2794)
			(stroke
				(width 0.1)
				(type default)
			)
			(layer "B.Fab")
		)
		(fp_line
			(start 0.12065 0.2794)
			(end 0.12065 0.3048)
			(stroke
				(width 0.1)
				(type default)
			)
			(layer "B.Fab")
		)
		(fp_line
			(start -0.12065 -0.2794)
			(end -0.12065 -0.3048)
			(stroke
				(width 0.1)
				(type default)
			)
			(layer "B.Fab")
		)
		(fp_line
			(start 0.12065 -0.2794)
			(end -0.12065 -0.2794)
			(stroke
				(width 0.1)
				(type default)
			)
			(layer "B.Fab")
		)
		(fp_line
			(start -0.67945 -0.3048)
			(end -0.67945 0.3048)
			(stroke
				(width 0.1)
				(type default)
			)
			(layer "B.Fab")
		)
		(fp_line
			(start -0.12065 -0.3048)
			(end -0.67945 -0.3048)
			(stroke
				(width 0.1)
				(type default)
			)
			(layer "B.Fab")
		)
		(fp_line
			(start 0.12065 -0.305054)
			(end 0.12065 -0.2794)
			(stroke
				(width 0.1)
				(type default)
			)
			(layer "B.Fab")
		)
		(fp_line
			(start 0.67945 -0.305054)
			(end 0.12065 -0.305054)
			(stroke
				(width 0.1)
				(type default)
			)
			(layer "B.Fab")
		)
		(pad "1" smd circle
			(at 0.40005 0 90)
			(size 0 0)
			(layers "B.Cu" "B.Mask" "B.Paste")
			(net "P3V3_USB_8042")
		)
		(pad "2" smd circle
			(at -0.40005 0 90)
			(size 0 0)
			(layers "B.Cu" "B.Mask" "B.Paste")
			(net "GND")
		)
	)
	(footprint ""
		(layer "B.Cu")
		(at 350.65716 -317.706756)
		(property "Reference" "C4378"
			(at 0 0 0)
			(layer "B.SilkS")
			(hide yes)
			(effects
				(font
					(size 1.27 1.27)
				)
				(justify mirror)
			)
		)
		(property "Value" ""
			(at 0 0 0)
			(layer "B.Fab")
			(effects
				(font
					(size 1.27 1.27)
				)
				(justify mirror)
			)
		)
		(duplicate_pad_numbers_are_jumpers no)
		(fp_line
			(start -0.299974 -0.150114)
			(end -0.299974 0.150114)
			(stroke
				(width 0.1)
				(type default)
			)
			(layer "B.Fab")
		)
		(fp_line
			(start -0.299974 0.150114)
			(end 0.299974 0.150114)
			(stroke
				(width 0.1)
				(type default)
			)
			(layer "B.Fab")
		)
		(fp_line
			(start 0.299974 -0.150114)
			(end -0.299974 -0.150114)
			(stroke
				(width 0.1)
				(type default)
			)
			(layer "B.Fab")
		)
		(fp_line
			(start 0.299974 0.150114)
			(end 0.299974 -0.150114)
			(stroke
				(width 0.1)
				(type default)
			)
			(layer "B.Fab")
		)
		(pad "1" smd rect
			(at 0.2667 0 180)
			(size 0.3048 0.381)
			(layers "B.Cu" "B.Mask" "B.Paste")
			(net "P0V8_SERDES_VDDA_PEX3")
		)
		(pad "2" smd rect
			(at -0.2667 0 180)
			(size 0.3048 0.381)
			(layers "B.Cu" "B.Mask" "B.Paste")
			(net "GND")
		)
	)
	(footprint ""
		(layer "B.Cu")
		(at 5.401818 -381.906526 180)
		(property "Reference" "C4465"
			(at 0 0 0)
			(layer "B.SilkS")
			(hide yes)
			(effects
				(font
					(size 1.27 1.27)
				)
				(justify mirror)
			)
		)
		(property "Value" ""
			(at 0 0 0)
			(layer "B.Fab")
			(effects
				(font
					(size 1.27 1.27)
				)
				(justify mirror)
			)
		)
		(duplicate_pad_numbers_are_jumpers no)
		(fp_line
			(start 1.524 0.762)
			(end 1.524 -0.762)
			(stroke
				(width 0.1524)
				(type default)
			)
			(layer "B.SilkS")
		)
		(fp_line
			(start 1.524 -0.762)
			(end -1.524 -0.762)
			(stroke
				(width 0.1524)
				(type default)
			)
			(layer "B.SilkS")
		)
		(fp_line
			(start -1.524 0.762)
			(end 1.524 0.762)
			(stroke
				(width 0.1524)
				(type default)
			)
			(layer "B.SilkS")
		)
		(fp_line
			(start -1.524 -0.762)
			(end -1.524 0.762)
			(stroke
				(width 0.1524)
				(type default)
			)
			(layer "B.SilkS")
		)
		(fp_line
			(start 1.1049 0.724916)
			(end -1.1049 0.724916)
			(stroke
				(width 0.1)
				(type default)
			)
			(layer "B.Fab")
		)
		(fp_line
			(start 1.1049 -0.724916)
			(end 1.1049 0.724916)
			(stroke
				(width 0.1)
				(type default)
			)
			(layer "B.Fab")
		)
		(fp_line
			(start -1.1049 0.724916)
			(end -1.1049 -0.724916)
			(stroke
				(width 0.1)
				(type default)
			)
			(layer "B.Fab")
		)
		(fp_line
			(start -1.1049 -0.724916)
			(end 1.1049 -0.724916)
			(stroke
				(width 0.1)
				(type default)
			)
			(layer "B.Fab")
		)
		(pad "1" smd rect
			(at 0.889 0 180)
			(size 1.016 1.27)
			(layers "B.Cu" "B.Mask" "B.Paste")
			(net "P3V3_USB_8042")
		)
		(pad "2" smd rect
			(at -0.889 0 180)
			(size 1.016 1.27)
			(layers "B.Cu" "B.Mask" "B.Paste")
			(net "GND")
		)
	)
	(footprint ""
		(layer "B.Cu")
		(at 397.54556 -296.37482)
		(property "Reference" "C1892"
			(at 0 0 0)
			(layer "B.SilkS")
			(hide yes)
			(effects
				(font
					(size 1.27 1.27)
				)
				(justify mirror)
			)
		)
		(property "Value" ""
			(at 0 0 0)
			(layer "B.Fab")
			(effects
				(font
					(size 1.27 1.27)
				)
				(justify mirror)
			)
		)
		(duplicate_pad_numbers_are_jumpers no)
		(fp_line
			(start -0.299974 -0.150114)
			(end -0.299974 0.150114)
			(stroke
				(width 0.1)
				(type default)
			)
			(layer "B.Fab")
		)
		(fp_line
			(start -0.299974 0.150114)
			(end 0.299974 0.150114)
			(stroke
				(width 0.1)
				(type default)
			)
			(layer "B.Fab")
		)
		(fp_line
			(start 0.299974 -0.150114)
			(end -0.299974 -0.150114)
			(stroke
				(width 0.1)
				(type default)
			)
			(layer "B.Fab")
		)
		(fp_line
			(start 0.299974 0.150114)
			(end 0.299974 -0.150114)
			(stroke
				(width 0.1)
				(type default)
			)
			(layer "B.Fab")
		)
		(pad "1" smd rect
			(at 0.2667 0 180)
			(size 0.3048 0.381)
			(layers "B.Cu" "B.Mask" "B.Paste")
			(net "P0V8_PEX3")
		)
		(pad "2" smd rect
			(at -0.2667 0 180)
			(size 0.3048 0.381)
			(layers "B.Cu" "B.Mask" "B.Paste")
			(net "GND")
		)
	)
	(footprint ""
		(layer "B.Cu")
		(at 172.900086 -303.499774 -90)
		(property "Reference" "C3090"
			(at 0 0 90)
			(layer "B.SilkS")
			(hide yes)
			(effects
				(font
					(size 1.27 1.27)
				)
				(justify mirror)
			)
		)
		(property "Value" ""
			(at 0 0 90)
			(layer "B.Fab")
			(effects
				(font
					(size 1.27 1.27)
				)
				(justify mirror)
			)
		)
		(duplicate_pad_numbers_are_jumpers no)
		(fp_line
			(start -0.299974 0.150114)
			(end 0.299974 0.150114)
			(stroke
				(width 0.1)
				(type default)
			)
			(layer "B.Fab")
		)
		(fp_line
			(start 0.299974 0.150114)
			(end 0.299974 -0.150114)
			(stroke
				(width 0.1)
				(type default)
			)
			(layer "B.Fab")
		)
		(fp_line
			(start -0.299974 -0.150114)
			(end -0.299974 0.150114)
			(stroke
				(width 0.1)
				(type default)
			)
			(layer "B.Fab")
		)
		(fp_line
			(start 0.299974 -0.150114)
			(end -0.299974 -0.150114)
			(stroke
				(width 0.1)
				(type default)
			)
			(layer "B.Fab")
		)
		(pad "1" smd rect
			(at 0.2667 0 90)
			(size 0.3048 0.381)
			(layers "B.Cu" "B.Mask" "B.Paste")
			(net "P1V25_PEX1")
		)
		(pad "2" smd rect
			(at -0.2667 0 90)
			(size 0.3048 0.381)
			(layers "B.Cu" "B.Mask" "B.Paste")
			(net "GND")
		)
	)
	(footprint ""
		(layer "B.Cu")
		(at 243.3193 -206.588868 180)
		(property "Reference" "C2015"
			(at 0 0 0)
			(layer "B.SilkS")
			(hide yes)
			(effects
				(font
					(size 1.27 1.27)
				)
				(justify mirror)
			)
		)
		(property "Value" ""
			(at 0 0 0)
			(layer "B.Fab")
			(effects
				(font
					(size 1.27 1.27)
				)
				(justify mirror)
			)
		)
		(duplicate_pad_numbers_are_jumpers no)
		(fp_line
			(start 1.2954 0.5842)
			(end 1.2954 -0.5842)
			(stroke
				(width 0.1524)
				(type default)
			)
			(layer "B.SilkS")
		)
		(fp_line
			(start 1.2954 -0.5842)
			(end -1.2954 -0.5842)
			(stroke
				(width 0.1524)
				(type default)
			)
			(layer "B.SilkS")
		)
		(fp_line
			(start -1.2954 0.5842)
			(end 1.2954 0.5842)
			(stroke
				(width 0.1524)
				(type default)
			)
			(layer "B.SilkS")
		)
		(fp_line
			(start -1.2954 -0.5842)
			(end -1.2954 0.5842)
			(stroke
				(width 0.1524)
				(type default)
			)
			(layer "B.SilkS")
		)
		(fp_line
			(start 1.1938 0.4064)
			(end 1.1938 -0.4064)
			(stroke
				(width 0.1)
				(type default)
			)
			(layer "B.Fab")
		)
		(fp_line
			(start 1.1938 -0.4064)
			(end 0.8636 -0.4064)
			(stroke
				(width 0.1)
				(type default)
			)
			(layer "B.Fab")
		)
		(fp_line
			(start 0.8636 0.4572)
			(end 0.8636 0.4064)
			(stroke
				(width 0.1)
				(type default)
			)
			(layer "B.Fab")
		)
		(fp_line
			(start 0.8636 0.4064)
			(end 1.1938 0.4064)
			(stroke
				(width 0.1)
				(type default)
			)
			(layer "B.Fab")
		)
		(fp_line
			(start 0.8636 -0.4064)
			(end 0.8636 -0.4572)
			(stroke
				(width 0.1)
				(type default)
			)
			(layer "B.Fab")
		)
		(fp_line
			(start 0.8636 -0.4572)
			(end -0.8636 -0.4572)
			(stroke
				(width 0.1)
				(type default)
			)
			(layer "B.Fab")
		)
		(fp_line
			(start -0.8636 0.4572)
			(end 0.8636 0.4572)
			(stroke
				(width 0.1)
				(type default)
			)
			(layer "B.Fab")
		)
		(fp_line
			(start -0.8636 0.4064)
			(end -0.8636 0.4572)
			(stroke
				(width 0.1)
				(type default)
			)
			(layer "B.Fab")
		)
		(fp_line
			(start -0.8636 -0.4064)
			(end -1.1938 -0.4064)
			(stroke
				(width 0.1)
				(type default)
			)
			(layer "B.Fab")
		)
		(fp_line
			(start -0.8636 -0.4572)
			(end -0.8636 -0.4064)
			(stroke
				(width 0.1)
				(type default)
			)
			(layer "B.Fab")
		)
		(fp_line
			(start -1.1938 0.4064)
			(end -0.8636 0.4064)
			(stroke
				(width 0.1)
				(type default)
			)
			(layer "B.Fab")
		)
		(fp_line
			(start -1.1938 -0.4064)
			(end -1.1938 0.4064)
			(stroke
				(width 0.1)
				(type default)
			)
			(layer "B.Fab")
		)
		(pad "1" smd rect
			(at 0.7366 0 90)
			(size 0.7112 0.8128)
			(layers "B.Cu" "B.Mask" "B.Paste")
			(net "P1V2_AUX")
		)
		(pad "2" smd rect
			(at -0.7366 0 90)
			(size 0.7112 0.8128)
			(layers "B.Cu" "B.Mask" "B.Paste")
			(net "GND")
		)
	)
	(footprint ""
		(layer "B.Cu")
		(at 335.72958 -87.890604 180)
		(property "Reference" "C2682"
			(at 0 0 0)
			(layer "B.SilkS")
			(hide yes)
			(effects
				(font
					(size 1.27 1.27)
				)
				(justify mirror)
			)
		)
		(property "Value" ""
			(at 0 0 0)
			(layer "B.Fab")
			(effects
				(font
					(size 1.27 1.27)
				)
				(justify mirror)
			)
		)
		(duplicate_pad_numbers_are_jumpers no)
		(fp_line
			(start 0.7874 0.4064)
			(end 0.7874 -0.4064)
			(stroke
				(width 0.1524)
				(type default)
			)
			(layer "B.SilkS")
		)
		(fp_line
			(start 0.7874 -0.4064)
			(end -0.7874 -0.4064)
			(stroke
				(width 0.1524)
				(type default)
			)
			(layer "B.SilkS")
		)
		(fp_line
			(start -0.7874 0.4064)
			(end 0.7874 0.4064)
			(stroke
				(width 0.1524)
				(type default)
			)
			(layer "B.SilkS")
		)
		(fp_line
			(start -0.7874 -0.4064)
			(end -0.7874 0.4064)
			(stroke
				(width 0.1524)
				(type default)
			)
			(layer "B.SilkS")
		)
		(fp_line
			(start 0.67945 0.3048)
			(end 0.67945 -0.305054)
			(stroke
				(width 0.1)
				(type default)
			)
			(layer "B.Fab")
		)
		(fp_line
			(start 0.67945 -0.305054)
			(end 0.12065 -0.305054)
			(stroke
				(width 0.1)
				(type default)
			)
			(layer "B.Fab")
		)
		(fp_line
			(start 0.12065 0.3048)
			(end 0.67945 0.3048)
			(stroke
				(width 0.1)
				(type default)
			)
			(layer "B.Fab")
		)
		(fp_line
			(start 0.12065 0.2794)
			(end 0.12065 0.3048)
			(stroke
				(width 0.1)
				(type default)
			)
			(layer "B.Fab")
		)
		(fp_line
			(start 0.12065 -0.2794)
			(end -0.12065 -0.2794)
			(stroke
				(width 0.1)
				(type default)
			)
			(layer "B.Fab")
		)
		(fp_line
			(start 0.12065 -0.305054)
			(end 0.12065 -0.2794)
			(stroke
				(width 0.1)
				(type default)
			)
			(layer "B.Fab")
		)
		(fp_line
			(start -0.120396 0.3048)
			(end -0.120396 0.2794)
			(stroke
				(width 0.1)
				(type default)
			)
			(layer "B.Fab")
		)
		(fp_line
			(start -0.120396 0.2794)
			(end 0.12065 0.2794)
			(stroke
				(width 0.1)
				(type default)
			)
			(layer "B.Fab")
		)
		(fp_line
			(start -0.12065 -0.2794)
			(end -0.12065 -0.3048)
			(stroke
				(width 0.1)
				(type default)
			)
			(layer "B.Fab")
		)
		(fp_line
			(start -0.12065 -0.3048)
			(end -0.67945 -0.3048)
			(stroke
				(width 0.1)
				(type default)
			)
			(layer "B.Fab")
		)
		(fp_line
			(start -0.67945 0.3048)
			(end -0.120396 0.3048)
			(stroke
				(width 0.1)
				(type default)
			)
			(layer "B.Fab")
		)
		(fp_line
			(start -0.67945 -0.3048)
			(end -0.67945 0.3048)
			(stroke
				(width 0.1)
				(type default)
			)
			(layer "B.Fab")
		)
		(pad "1" smd circle
			(at 0.40005 0)
			(size 0 0)
			(layers "B.Cu" "B.Mask" "B.Paste")
			(net "P3V3_VDDAR_9ZXL0851_8_15")
		)
		(pad "2" smd circle
			(at -0.40005 0)
			(size 0 0)
			(layers "B.Cu" "B.Mask" "B.Paste")
			(net "GND")
		)
	)
	(footprint ""
		(layer "B.Cu")
		(at 261.536942 -81.001616 -90)
		(property "Reference" "C2631"
			(at 0 0 90)
			(layer "B.SilkS")
			(hide yes)
			(effects
				(font
					(size 1.27 1.27)
				)
				(justify mirror)
			)
		)
		(property "Value" ""
			(at 0 0 90)
			(layer "B.Fab")
			(effects
				(font
					(size 1.27 1.27)
				)
				(justify mirror)
			)
		)
		(duplicate_pad_numbers_are_jumpers no)
		(fp_line
			(start -0.7874 0.4064)
			(end 0.7874 0.4064)
			(stroke
				(width 0.1524)
				(type default)
			)
			(layer "B.SilkS")
		)
		(fp_line
			(start 0.7874 0.4064)
			(end 0.7874 -0.4064)
			(stroke
				(width 0.1524)
				(type default)
			)
			(layer "B.SilkS")
		)
		(fp_line
			(start -0.7874 -0.4064)
			(end -0.7874 0.4064)
			(stroke
				(width 0.1524)
				(type default)
			)
			(layer "B.SilkS")
		)
		(fp_line
			(start 0.7874 -0.4064)
			(end -0.7874 -0.4064)
			(stroke
				(width 0.1524)
				(type default)
			)
			(layer "B.SilkS")
		)
		(fp_line
			(start -0.67945 0.3048)
			(end -0.120396 0.3048)
			(stroke
				(width 0.1)
				(type default)
			)
			(layer "B.Fab")
		)
		(fp_line
			(start -0.120396 0.3048)
			(end -0.120396 0.2794)
			(stroke
				(width 0.1)
				(type default)
			)
			(layer "B.Fab")
		)
		(fp_line
			(start 0.12065 0.3048)
			(end 0.67945 0.3048)
			(stroke
				(width 0.1)
				(type default)
			)
			(layer "B.Fab")
		)
		(fp_line
			(start 0.67945 0.3048)
			(end 0.67945 -0.305054)
			(stroke
				(width 0.1)
				(type default)
			)
			(layer "B.Fab")
		)
		(fp_line
			(start -0.120396 0.2794)
			(end 0.12065 0.2794)
			(stroke
				(width 0.1)
				(type default)
			)
			(layer "B.Fab")
		)
		(fp_line
			(start 0.12065 0.2794)
			(end 0.12065 0.3048)
			(stroke
				(width 0.1)
				(type default)
			)
			(layer "B.Fab")
		)
		(fp_line
			(start -0.12065 -0.2794)
			(end -0.12065 -0.3048)
			(stroke
				(width 0.1)
				(type default)
			)
			(layer "B.Fab")
		)
		(fp_line
			(start 0.12065 -0.2794)
			(end -0.12065 -0.2794)
			(stroke
				(width 0.1)
				(type default)
			)
			(layer "B.Fab")
		)
		(fp_line
			(start -0.67945 -0.3048)
			(end -0.67945 0.3048)
			(stroke
				(width 0.1)
				(type default)
			)
			(layer "B.Fab")
		)
		(fp_line
			(start -0.12065 -0.3048)
			(end -0.67945 -0.3048)
			(stroke
				(width 0.1)
				(type default)
			)
			(layer "B.Fab")
		)
		(fp_line
			(start 0.12065 -0.305054)
			(end 0.12065 -0.2794)
			(stroke
				(width 0.1)
				(type default)
			)
			(layer "B.Fab")
		)
		(fp_line
			(start 0.67945 -0.305054)
			(end 0.12065 -0.305054)
			(stroke
				(width 0.1)
				(type default)
			)
			(layer "B.Fab")
		)
		(pad "1" smd circle
			(at 0.40005 0 90)
			(size 0 0)
			(layers "B.Cu" "B.Mask" "B.Paste")
			(net "P3V3_CLK_GEN_VDD_CK440")
		)
		(pad "2" smd circle
			(at -0.40005 0 90)
			(size 0 0)
			(layers "B.Cu" "B.Mask" "B.Paste")
			(net "GND")
		)
	)
)
